(kicad_pcb
	(version 20241229)
	(generator "pcbnew")
	(generator_version "9.0")
	(general
		(thickness 1.61)
		(legacy_teardrops no)
	)
	(paper "A3")
	(title_block
		(title "RDIMM DDR5 Tester")
		(date "2026-05-21")
		(rev "2.2.0")
		(company "Antmicro")
		(comment 9 "footprints 357-361 of 796")
	)
	(layers
		(0 "F.Cu" signal)
		(4 "In1.Cu" power)
		(6 "In2.Cu" mixed)
		(8 "In3.Cu" power)
		(10 "In4.Cu" mixed)
		(12 "In5.Cu" power)
		(14 "In6.Cu" mixed)
		(16 "In7.Cu" power)
		(18 "In8.Cu" power)
		(20 "In9.Cu" mixed)
		(22 "In10.Cu" power)
		(2 "B.Cu" signal)
		(9 "F.Adhes" user "F.Adhesive")
		(11 "B.Adhes" user "B.Adhesive")
		(13 "F.Paste" user)
		(15 "B.Paste" user)
		(5 "F.SilkS" user "F.Silkscreen")
		(7 "B.SilkS" user "B.Silkscreen")
		(1 "F.Mask" user)
		(3 "B.Mask" user)
		(17 "Dwgs.User" user "User.Drawings")
		(19 "Cmts.User" user "User.Comments")
		(21 "Eco1.User" user "User.Eco1")
		(23 "Eco2.User" user "User.Eco2")
		(25 "Edge.Cuts" user)
		(27 "Margin" user)
		(31 "F.CrtYd" user "F.Courtyard")
		(29 "B.CrtYd" user "B.Courtyard")
		(35 "F.Fab" user)
		(33 "B.Fab" user)
	)
	(footprint "antmicro-footprints:R_0402_1005Metric"
		(layer "F.Cu")
		(at 140.824499 178.449 90)
		(descr "Resistor SMD 0402")
		(tags "resistor SMD 0402")
		(property "Reference" "R79"
			(at -1.122484 1.400501 90)
			(layer "F.SilkS")
			(effects
				(font
					(size 0.7 0.7)
					(thickness 0.15)
				)
				(justify left bottom)
			)
		)
		(property "Value" "R_10k_0402"
			(at -1.011843 1.772047 90)
			(layer "F.Fab")
			(effects
				(font
					(size 0.7 0.7)
					(thickness 0.15)
				)
				(justify left bottom)
			)
		)
		(property "Datasheet" "https://www.bourns.com/docs/product-datasheets/cr.pdf"
			(at 0 0 90)
			(layer "F.Fab")
			(hide yes)
			(effects
				(font
					(size 1.27 1.27)
					(thickness 0.15)
				)
			)
		)
		(property "Manufacturer" "Bourns"
			(at 0 0 90)
			(unlocked yes)
			(layer "F.Fab")
			(hide yes)
			(effects
				(font
					(size 1 1)
					(thickness 0.15)
				)
			)
		)
		(property "MPN" "CR0402-FX-1002GLF"
			(at 0 0 90)
			(unlocked yes)
			(layer "F.Fab")
			(hide yes)
			(effects
				(font
					(size 1 1)
					(thickness 0.15)
				)
			)
		)
		(property "Val" "10k"
			(at 0 0 90)
			(unlocked yes)
			(layer "F.Fab")
			(hide yes)
			(effects
				(font
					(size 1 1)
					(thickness 0.15)
				)
			)
		)
		(property "License" "Apache-2.0"
			(at 0 0 90)
			(unlocked yes)
			(layer "F.Fab")
			(hide yes)
			(effects
				(font
					(size 1 1)
					(thickness 0.15)
				)
			)
		)
		(property "Author" "Antmicro"
			(at 0 0 90)
			(unlocked yes)
			(layer "F.Fab")
			(hide yes)
			(effects
				(font
					(size 1 1)
					(thickness 0.15)
				)
			)
		)
		(property "Tolerance" "1%"
			(at 0 0 90)
			(unlocked yes)
			(layer "F.Fab")
			(hide yes)
			(effects
				(font
					(size 1 1)
					(thickness 0.15)
				)
			)
		)
		(sheetname "/Debug FTDI + VNA/")
		(sheetfile "debug-ftdi.kicad_sch")
		(attr smd)
		(fp_rect
			(start -0.925 -0.47)
			(end 0.925 0.47)
			(stroke
				(width 0.05)
				(type default)
			)
			(fill no)
			(layer "F.CrtYd")
		)
		(fp_rect
			(start -0.5 -0.25)
			(end 0.5 0.25)
			(stroke
				(width 0.15)
				(type solid)
			)
			(fill no)
			(layer "F.Fab")
		)
		(fp_text user "Author: Antmicro"
			(at -0.95 4.169 90)
			(layer "F.Fab")
			(effects
				(font
					(size 0.7 0.7)
					(thickness 0.15)
				)
				(justify left bottom)
			)
		)
		(fp_text user "License: Apache-2.0"
			(at -0.95 5.169 90)
			(layer "F.Fab")
			(effects
				(font
					(size 0.7 0.7)
					(thickness 0.15)
				)
				(justify left bottom)
			)
		)
		(fp_text user "${REFERENCE}"
			(at -0.95 3.168 90)
			(layer "F.Fab")
			(effects
				(font
					(size 0.7 0.7)
					(thickness 0.15)
				)
				(justify left bottom)
			)
		)
		(pad "1" smd roundrect
			(at -0.48 0 90)
			(size 0.59 0.64)
			(layers "F.Cu" "F.Mask" "F.Paste")
			(roundrect_rratio 0.25)
			(net 6 "/Debug FTDI + VNA/FTDI_3V3")
			(pintype "passive")
		)
		(pad "2" smd roundrect
			(at 0.48 0 90)
			(size 0.59 0.64)
			(layers "F.Cu" "F.Mask" "F.Paste")
			(roundrect_rratio 0.25)
			(net 372 "/Debug FTDI + VNA/FTDI_PWREN")
			(pintype "passive")
		)
	)
	(footprint "antmicro-footprints:C_0603_1608Metric"
		(layer "F.Cu")
		(at 232.65 168.755 180)
		(descr "Capacitor SMD 0603")
		(tags "capacitor 0603")
		(property "Reference" "C262"
			(at -4.025 -0.395001 0)
			(layer "F.SilkS")
			(effects
				(font
					(size 0.7 0.7)
					(thickness 0.15)
				)
				(justify right bottom)
			)
		)
		(property "Value" "C_22u_0603"
			(at -1.42757 1.770288 0)
			(layer "F.Fab")
			(effects
				(font
					(size 0.7 0.7)
					(thickness 0.15)
				)
				(justify right bottom)
			)
		)
		(property "Datasheet" "https://www.murata.com/products/productdetail?partno=GRM188R60J226MEA0%23"
			(at 0 0 180)
			(layer "F.Fab")
			(hide yes)
			(effects
				(font
					(size 1.27 1.27)
					(thickness 0.15)
				)
			)
		)
		(property "Manufacturer" "Murata"
			(at 0 0 180)
			(unlocked yes)
			(layer "F.Fab")
			(hide yes)
			(effects
				(font
					(size 1 1)
					(thickness 0.15)
				)
			)
		)
		(property "MPN" "GRM188R60J226MEA0D"
			(at 0 0 180)
			(unlocked yes)
			(layer "F.Fab")
			(hide yes)
			(effects
				(font
					(size 1 1)
					(thickness 0.15)
				)
			)
		)
		(property "Val" "22u"
			(at 0 0 180)
			(unlocked yes)
			(layer "F.Fab")
			(hide yes)
			(effects
				(font
					(size 1 1)
					(thickness 0.15)
				)
			)
		)
		(property "License" "Apache-2.0"
			(at 0 0 180)
			(unlocked yes)
			(layer "F.Fab")
			(hide yes)
			(effects
				(font
					(size 1 1)
					(thickness 0.15)
				)
			)
		)
		(property "Author" "Antmicro"
			(at 0 0 180)
			(unlocked yes)
			(layer "F.Fab")
			(hide yes)
			(effects
				(font
					(size 1 1)
					(thickness 0.15)
				)
			)
		)
		(property "Voltage" ""
			(at 0 0 180)
			(unlocked yes)
			(layer "F.Fab")
			(hide yes)
			(effects
				(font
					(size 1 1)
					(thickness 0.15)
				)
			)
		)
		(property "Dielectric" ""
			(at 0 0 180)
			(unlocked yes)
			(layer "F.Fab")
			(hide yes)
			(effects
				(font
					(size 1 1)
					(thickness 0.15)
				)
			)
		)
		(sheetname "/Supply/DC-DC VCCINT/")
		(sheetfile "dc-dc-vccint.kicad_sch")
		(attr smd)
		(fp_line
			(start -0.15 0.4)
			(end 0.15 0.4)
			(stroke
				(width 0.15)
				(type solid)
			)
			(layer "F.SilkS")
		)
		(fp_line
			(start -0.15 -0.4)
			(end 0.15 -0.4)
			(stroke
				(width 0.15)
				(type solid)
			)
			(layer "F.SilkS")
		)
		(fp_rect
			(start -1.25 -0.65)
			(end 1.25 0.65)
			(stroke
				(width 0.05)
				(type solid)
			)
			(fill no)
			(layer "F.CrtYd")
		)
		(fp_rect
			(start -0.8 -0.4)
			(end 0.8 0.4)
			(stroke
				(width 0.15)
				(type solid)
			)
			(fill no)
			(layer "F.Fab")
		)
		(fp_text user "${REFERENCE}"
			(at -1.682 3.895 180)
			(layer "F.Fab")
			(effects
				(font
					(size 0.7 0.7)
					(thickness 0.15)
				)
				(justify left bottom)
			)
		)
		(fp_text user "License: Apache-2.0"
			(at -1.682 5.895 180)
			(layer "F.Fab")
			(effects
				(font
					(size 0.7 0.7)
					(thickness 0.15)
				)
				(justify left bottom)
			)
		)
		(fp_text user "Author: Antmicro"
			(at -1.682 4.894 180)
			(layer "F.Fab")
			(effects
				(font
					(size 0.7 0.7)
					(thickness 0.15)
				)
				(justify left bottom)
			)
		)
		(pad "1" smd roundrect
			(at -0.7 0 180)
			(size 0.8 1)
			(layers "F.Cu" "F.Mask" "F.Paste")
			(roundrect_rratio 0.2)
			(net 1 "GND")
			(pintype "passive")
		)
		(pad "2" smd roundrect
			(at 0.7 0 180)
			(size 0.8 1)
			(layers "F.Cu" "F.Mask" "F.Paste")
			(roundrect_rratio 0.2)
			(net 224 "/Supply/DC-DC VCCINT/0V85_REG1")
			(pintype "passive")
		)
	)
	(footprint "antmicro-footprints:C_0603_1608Metric"
		(layer "F.Cu")
		(at 248.87 171.372001 90)
		(descr "Capacitor SMD 0603")
		(tags "capacitor 0603")
		(property "Reference" "C186"
			(at 1.272001 0.48 90)
			(layer "F.SilkS")
			(effects
				(font
					(size 0.7 0.7)
					(thickness 0.15)
				)
				(justify left bottom)
			)
		)
		(property "Value" "C_22u_0603"
			(at -1.42757 1.770288 90)
			(layer "F.Fab")
			(effects
				(font
					(size 0.7 0.7)
					(thickness 0.15)
				)
				(justify left bottom)
			)
		)
		(property "Datasheet" "https://www.murata.com/products/productdetail?partno=GRM188R60J226MEA0%23"
			(at 0 0 90)
			(layer "F.Fab")
			(hide yes)
			(effects
				(font
					(size 1.27 1.27)
					(thickness 0.15)
				)
			)
		)
		(property "Manufacturer" "Murata"
			(at 0 0 90)
			(unlocked yes)
			(layer "F.Fab")
			(hide yes)
			(effects
				(font
					(size 1 1)
					(thickness 0.15)
				)
			)
		)
		(property "MPN" "GRM188R60J226MEA0D"
			(at 0 0 90)
			(unlocked yes)
			(layer "F.Fab")
			(hide yes)
			(effects
				(font
					(size 1 1)
					(thickness 0.15)
				)
			)
		)
		(property "Val" "22u"
			(at 0 0 90)
			(unlocked yes)
			(layer "F.Fab")
			(hide yes)
			(effects
				(font
					(size 1 1)
					(thickness 0.15)
				)
			)
		)
		(property "License" "Apache-2.0"
			(at 0 0 90)
			(unlocked yes)
			(layer "F.Fab")
			(hide yes)
			(effects
				(font
					(size 1 1)
					(thickness 0.15)
				)
			)
		)
		(property "Author" "Antmicro"
			(at 0 0 90)
			(unlocked yes)
			(layer "F.Fab")
			(hide yes)
			(effects
				(font
					(size 1 1)
					(thickness 0.15)
				)
			)
		)
		(property "Voltage" ""
			(at 0 0 90)
			(unlocked yes)
			(layer "F.Fab")
			(hide yes)
			(effects
				(font
					(size 1 1)
					(thickness 0.15)
				)
			)
		)
		(property "Dielectric" ""
			(at 0 0 90)
			(unlocked yes)
			(layer "F.Fab")
			(hide yes)
			(effects
				(font
					(size 1 1)
					(thickness 0.15)
				)
			)
		)
		(sheetname "/Supply/DC-DC AUX, MGT/")
		(sheetfile "dc-dc-aux-mgt.kicad_sch")
		(attr smd)
		(fp_line
			(start -0.15 -0.4)
			(end 0.15 -0.4)
			(stroke
				(width 0.15)
				(type solid)
			)
			(layer "F.SilkS")
		)
		(fp_line
			(start -0.15 0.4)
			(end 0.15 0.4)
			(stroke
				(width 0.15)
				(type solid)
			)
			(layer "F.SilkS")
		)
		(fp_rect
			(start -1.25 -0.65)
			(end 1.25 0.65)
			(stroke
				(width 0.05)
				(type solid)
			)
			(fill no)
			(layer "F.CrtYd")
		)
		(fp_rect
			(start -0.8 -0.4)
			(end 0.8 0.4)
			(stroke
				(width 0.15)
				(type solid)
			)
			(fill no)
			(layer "F.Fab")
		)
		(fp_text user "License: Apache-2.0"
			(at -1.682 5.895 90)
			(layer "F.Fab")
			(effects
				(font
					(size 0.7 0.7)
					(thickness 0.15)
				)
				(justify left bottom)
			)
		)
		(fp_text user "Author: Antmicro"
			(at -1.682 4.894 90)
			(layer "F.Fab")
			(effects
				(font
					(size 0.7 0.7)
					(thickness 0.15)
				)
				(justify left bottom)
			)
		)
		(fp_text user "${REFERENCE}"
			(at -1.682 3.895 90)
			(layer "F.Fab")
			(effects
				(font
					(size 0.7 0.7)
					(thickness 0.15)
				)
				(justify left bottom)
			)
		)
		(pad "1" smd roundrect
			(at -0.7 0 90)
			(size 0.8 1)
			(layers "F.Cu" "F.Mask" "F.Paste")
			(roundrect_rratio 0.2)
			(net 1 "GND")
			(pintype "passive")
		)
		(pad "2" smd roundrect
			(at 0.7 0 90)
			(size 0.8 1)
			(layers "F.Cu" "F.Mask" "F.Paste")
			(roundrect_rratio 0.2)
			(net 48 "/Supply/DC-DC AUX, MGT/MGTAVTT_local")
			(pintype "passive")
		)
	)
	(footprint "antmicro-footprints:C_0402_1005Metric"
		(layer "F.Cu")
		(at 232 179.175 180)
		(descr "Capacitor SMD 0402")
		(tags "capacitor SMD 0402")
		(property "Reference" "C213"
			(at 0.94 -0.465 0)
			(layer "F.SilkS")
			(effects
				(font
					(size 0.7 0.7)
					(thickness 0.15)
				)
				(justify right bottom)
			)
		)
		(property "Value" "C_1u_25V_0402"
			(at -1.022927 2.155213 0)
			(layer "F.Fab")
			(effects
				(font
					(size 0.7 0.7)
					(thickness 0.15)
				)
				(justify right bottom)
			)
		)
		(property "Datasheet" "https://www.murata.com/products/productdetail?partno=GRM155R61E105KE11%23"
			(at 0 0 180)
			(layer "F.Fab")
			(hide yes)
			(effects
				(font
					(size 1.27 1.27)
					(thickness 0.15)
				)
			)
		)
		(property "MPN" "GRM155R61E105KE11J"
			(at 0 0 180)
			(unlocked yes)
			(layer "F.Fab")
			(hide yes)
			(effects
				(font
					(size 1 1)
					(thickness 0.15)
				)
			)
		)
		(property "Manufacturer" "Murata"
			(at 0 0 180)
			(unlocked yes)
			(layer "F.Fab")
			(hide yes)
			(effects
				(font
					(size 1 1)
					(thickness 0.15)
				)
			)
		)
		(property "License" "Apache-2.0"
			(at 0 0 180)
			(unlocked yes)
			(layer "F.Fab")
			(hide yes)
			(effects
				(font
					(size 1 1)
					(thickness 0.15)
				)
			)
		)
		(property "Author" "Antmicro"
			(at 0 0 180)
			(unlocked yes)
			(layer "F.Fab")
			(hide yes)
			(effects
				(font
					(size 1 1)
					(thickness 0.15)
				)
			)
		)
		(property "Val" "1u"
			(at 0 0 180)
			(unlocked yes)
			(layer "F.Fab")
			(hide yes)
			(effects
				(font
					(size 1 1)
					(thickness 0.15)
				)
			)
		)
		(property "Voltage" "25V"
			(at 0 0 180)
			(unlocked yes)
			(layer "F.Fab")
			(hide yes)
			(effects
				(font
					(size 1 1)
					(thickness 0.15)
				)
			)
		)
		(property "Dielectric" "X5R"
			(at 0 0 180)
			(unlocked yes)
			(layer "F.Fab")
			(hide yes)
			(effects
				(font
					(size 1 1)
					(thickness 0.15)
				)
			)
		)
		(sheetname "/Supply/DC-DC VCCINT/")
		(sheetfile "dc-dc-vccint.kicad_sch")
		(attr smd)
		(fp_rect
			(start -0.925 -0.47)
			(end 0.925 0.47)
			(stroke
				(width 0.05)
				(type default)
			)
			(fill no)
			(layer "F.CrtYd")
		)
		(fp_line
			(start 0.504 0.248)
			(end -0.494 0.248)
			(stroke
				(width 0.15)
				(type solid)
			)
			(layer "F.Fab")
		)
		(fp_line
			(start 0.504 -0.25)
			(end 0.504 0.248)
			(stroke
				(width 0.15)
				(type solid)
			)
			(layer "F.Fab")
		)
		(fp_line
			(start -0.494 0.248)
			(end -0.494 -0.25)
			(stroke
				(width 0.15)
				(type solid)
			)
			(layer "F.Fab")
		)
		(fp_line
			(start -0.494 -0.25)
			(end 0.504 -0.25)
			(stroke
				(width 0.15)
				(type solid)
			)
			(layer "F.Fab")
		)
		(fp_text user "Author: Antmicro"
			(at -0.939 3.399 180)
			(layer "F.Fab")
			(effects
				(font
					(size 0.7 0.7)
					(thickness 0.15)
				)
				(justify left bottom)
			)
		)
		(fp_text user "${REFERENCE}"
			(at -0.939 4.599 180)
			(layer "F.Fab")
			(effects
				(font
					(size 0.7 0.7)
					(thickness 0.15)
				)
				(justify left bottom)
			)
		)
		(fp_text user "License: Apache-2.0"
			(at -0.939 5.799 180)
			(layer "F.Fab")
			(effects
				(font
					(size 0.7 0.7)
					(thickness 0.15)
				)
				(justify left bottom)
			)
		)
		(pad "1" smd roundrect
			(at -0.48 0 180)
			(size 0.59 0.64)
			(layers "F.Cu" "F.Mask" "F.Paste")
			(roundrect_rratio 0.25)
			(net 1 "GND")
			(pintype "passive")
		)
		(pad "2" smd roundrect
			(at 0.48 0 180)
			(size 0.59 0.64)
			(layers "F.Cu" "F.Mask" "F.Paste")
			(roundrect_rratio 0.25)
			(net 35 "VDC")
			(pintype "passive")
		)
	)
	(footprint "antmicro-footprints:C_0402_1005Metric"
		(layer "F.Cu")
		(at 235.57 132.32 90)
		(descr "Capacitor SMD 0402")
		(tags "capacitor SMD 0402")
		(property "Reference" "C166"
			(at -4.15 0.17 90)
			(layer "F.SilkS")
			(effects
				(font
					(size 0.7 0.7)
					(thickness 0.15)
				)
				(justify left bottom)
			)
		)
		(property "Value" "C_100n_0402"
			(at -1.022927 2.155213 90)
			(layer "F.Fab")
			(effects
				(font
					(size 0.7 0.7)
					(thickness 0.15)
				)
				(justify left bottom)
			)
		)
		(property "Datasheet" "https://www.murata.com/products/productdetail?partno=GRM155R61H104KE14%23"
			(at 0 0 90)
			(layer "F.Fab")
			(hide yes)
			(effects
				(font
					(size 1.27 1.27)
					(thickness 0.15)
				)
			)
		)
		(property "Manufacturer" "Murata"
			(at 0 0 90)
			(unlocked yes)
			(layer "F.Fab")
			(hide yes)
			(effects
				(font
					(size 1 1)
					(thickness 0.15)
				)
			)
		)
		(property "MPN" "GRM155R61H104KE14D"
			(at 0 0 90)
			(unlocked yes)
			(layer "F.Fab")
			(hide yes)
			(effects
				(font
					(size 1 1)
					(thickness 0.15)
				)
			)
		)
		(property "Val" "100n"
			(at 0 0 90)
			(unlocked yes)
			(layer "F.Fab")
			(hide yes)
			(effects
				(font
					(size 1 1)
					(thickness 0.15)
				)
			)
		)
		(property "License" "Apache-2.0"
			(at 0 0 90)
			(unlocked yes)
			(layer "F.Fab")
			(hide yes)
			(effects
				(font
					(size 1 1)
					(thickness 0.15)
				)
			)
		)
		(property "Author" "Antmicro"
			(at 0 0 90)
			(unlocked yes)
			(layer "F.Fab")
			(hide yes)
			(effects
				(font
					(size 1 1)
					(thickness 0.15)
				)
			)
		)
		(property "Voltage" "50V"
			(at 0 0 90)
			(unlocked yes)
			(layer "F.Fab")
			(hide yes)
			(effects
				(font
					(size 1 1)
					(thickness 0.15)
				)
			)
		)
		(property "Dielectric" "X5R"
			(at 0 0 90)
			(unlocked yes)
			(layer "F.Fab")
			(hide yes)
			(effects
				(font
					(size 1 1)
					(thickness 0.15)
				)
			)
		)
		(sheetname "/I^{2}C + I3C/")
		(sheetfile "i2c.kicad_sch")
		(attr smd)
		(fp_rect
			(start -0.925 -0.47)
			(end 0.925 0.47)
			(stroke
				(width 0.05)
				(type default)
			)
			(fill no)
			(layer "F.CrtYd")
		)
		(fp_line
			(start 0.504 -0.25)
			(end 0.504 0.248)
			(stroke
				(width 0.15)
				(type solid)
			)
			(layer "F.Fab")
		)
		(fp_line
			(start -0.494 -0.25)
			(end 0.504 -0.25)
			(stroke
				(width 0.15)
				(type solid)
			)
			(layer "F.Fab")
		)
		(fp_line
			(start 0.504 0.248)
			(end -0.494 0.248)
			(stroke
				(width 0.15)
				(type solid)
			)
			(layer "F.Fab")
		)
		(fp_line
			(start -0.494 0.248)
			(end -0.494 -0.25)
			(stroke
				(width 0.15)
				(type solid)
			)
			(layer "F.Fab")
		)
		(fp_text user "Author: Antmicro"
			(at -0.939 3.399 90)
			(layer "F.Fab")
			(effects
				(font
					(size 0.7 0.7)
					(thickness 0.15)
				)
				(justify left bottom)
			)
		)
		(fp_text user "${REFERENCE}"
			(at -0.939 4.599 90)
			(layer "F.Fab")
			(effects
				(font
					(size 0.7 0.7)
					(thickness 0.15)
				)
				(justify left bottom)
			)
		)
		(fp_text user "License: Apache-2.0"
			(at -0.939 5.799 90)
			(layer "F.Fab")
			(effects
				(font
					(size 0.7 0.7)
					(thickness 0.15)
				)
				(justify left bottom)
			)
		)
		(pad "1" smd roundrect
			(at -0.48 0 90)
			(size 0.59 0.64)
			(layers "F.Cu" "F.Mask" "F.Paste")
			(roundrect_rratio 0.25)
			(net 201 "VDDSPD")
			(pintype "passive")
		)
		(pad "2" smd roundrect
			(at 0.48 0 90)
			(size 0.59 0.64)
			(layers "F.Cu" "F.Mask" "F.Paste")
			(roundrect_rratio 0.25)
			(net 1 "GND")
			(pintype "passive")
		)
	)
)
